FILE_TYPE = CONNECTIVITY;
{Allegro Design Entry HDL 17.2-2016 S081 (4005846) 1/11/2022}
"PAGE_NUMBER" = 45;
0"NC";
1"M_I_CPU1_SA_DQ<31:0>";
2"M_I_CPU1_SB_DQ<31:0>";
3"M_I_CPU1_SA_CB<7:0>";
4"M_I_CPU1_SB_CB<7:0>";
5"M_I_CPU1_SA_DQS_DP<9:0>";
6"M_I_CPU1_SB_DQS_DP<9:0>";
7"M_I_CPU1_SA_CA<6:0>";
8"M_I_CPU1_SB_CA<6:0>";
9"M_I_CPU1_SA_DQS_DN<9:0>";
10"M_I_CPU1_SB_DQS_DN<9:0>";
11"M_I_CPU1_ALERT_N";
12"TP_M_I_CPU1_SA_TEST39I";
13"M_I_CPU1_ALERT_R_N";
14"M_I_CPU1_CLK_DP<0>";
15"M_I_CPU1_CLK_DN<0>";
16"M_I_CPU1_SA_CS_N<1>";
17"M_I_CPU1_SA_RSP<0>";
18"M_I_CPU1_SA_CS_N<0>";
19"M_I_CPU1_SA_PAR";
20"M_I_CPU1_SB_CS_N<0>";
21"M_I_CPU1_SB_CS_N<1>";
22"M_I_CPU1_SB_RSP<0>";
23"M_I_CPU1_SB_PAR";
24"M_I_CPU1_RESET_N";
25"M_I_CPU1_SB_DQS_DN<9>";
26"M_I_CPU1_SB_DQS_DN<8>";
27"M_I_CPU1_SB_CA<6>";
28"M_I_CPU1_SA_CA<6>";
29"M_I_CPU1_SB_CA<5>";
30"M_I_CPU1_SA_CA<5>";
31"M_I_CPU1_SB_CA<4>";
32"M_I_CPU1_SA_CA<4>";
33"M_I_CPU1_SB_CA<3>";
34"M_I_CPU1_SA_CA<3>";
35"M_I_CPU1_SB_CA<2>";
36"M_I_CPU1_SA_CA<2>";
37"M_I_CPU1_SB_CA<1>";
38"M_I_CPU1_SA_CA<1>";
39"M_I_CPU1_SB_CA<0>";
40"M_I_CPU1_SA_CA<0>";
41"M_I_CPU1_SB_DQS_DP<9>";
42"M_I_CPU1_SB_DQS_DN<7>";
43"M_I_CPU1_SB_DQS_DN<6>";
44"M_I_CPU1_SB_DQS_DN<5>";
45"M_I_CPU1_SB_DQS_DN<4>";
46"M_I_CPU1_SA_DQS_DN<9>";
47"M_I_CPU1_SB_DQS_DN<3>";
48"M_I_CPU1_SA_DQS_DN<8>";
49"M_I_CPU1_SB_DQS_DN<2>";
50"M_I_CPU1_SB_DQS_DN<1>";
51"M_I_CPU1_SB_DQS_DN<0>";
52"M_I_CPU1_SB_DQS_DP<8>";
53"M_I_CPU1_SB_DQS_DP<7>";
54"M_I_CPU1_SB_DQS_DP<6>";
55"M_I_CPU1_SB_DQS_DP<5>";
56"M_I_CPU1_SB_DQS_DP<4>";
57"M_I_CPU1_SB_DQS_DP<3>";
58"M_I_CPU1_SA_DQS_DP<9>";
59"M_I_CPU1_SB_DQS_DP<2>";
60"M_I_CPU1_SB_DQS_DP<1>";
61"M_I_CPU1_SB_DQS_DP<0>";
62"M_I_CPU1_SA_DQS_DN<4>";
63"M_I_CPU1_SA_DQS_DN<3>";
64"M_I_CPU1_SA_DQS_DN<2>";
65"M_I_CPU1_SA_DQS_DN<1>";
66"M_I_CPU1_SA_DQS_DN<0>";
67"M_I_CPU1_SA_DQS_DN<7>";
68"M_I_CPU1_SA_DQS_DN<6>";
69"M_I_CPU1_SA_DQS_DN<5>";
70"M_I_CPU1_SA_DQS_DP<8>";
71"M_I_CPU1_SA_DQS_DP<7>";
72"M_I_CPU1_SA_DQS_DP<6>";
73"M_I_CPU1_SA_DQS_DP<5>";
74"M_I_CPU1_SA_DQS_DP<4>";
75"M_I_CPU1_SA_DQS_DP<0>";
76"M_I_CPU1_SA_DQS_DP<3>";
77"M_I_CPU1_SA_DQS_DP<2>";
78"M_I_CPU1_SA_DQS_DP<1>";
79"M_I_CPU1_SB_CB<2>";
80"M_I_CPU1_SA_CB<7>";
81"M_I_CPU1_SB_CB<1>";
82"M_I_CPU1_SB_CB<0>";
83"M_I_CPU1_SB_CB<7>";
84"M_I_CPU1_SB_CB<6>";
85"M_I_CPU1_SB_CB<5>";
86"M_I_CPU1_SB_CB<4>";
87"M_I_CPU1_SB_CB<3>";
88"M_I_CPU1_SB_DQ<22>";
89"M_I_CPU1_SB_DQ<21>";
90"M_I_CPU1_SA_CB<6>";
91"M_I_CPU1_SB_DQ<20>";
92"M_I_CPU1_SB_DQ<31>";
93"M_I_CPU1_SA_CB<5>";
94"M_I_CPU1_SB_DQ<30>";
95"M_I_CPU1_SA_CB<4>";
96"M_I_CPU1_SA_CB<3>";
97"M_I_CPU1_SA_CB<2>";
98"M_I_CPU1_SA_CB<1>";
99"M_I_CPU1_SA_CB<0>";
100"M_I_CPU1_SB_DQ<29>";
101"M_I_CPU1_SB_DQ<28>";
102"M_I_CPU1_SB_DQ<27>";
103"M_I_CPU1_SB_DQ<26>";
104"M_I_CPU1_SB_DQ<25>";
105"M_I_CPU1_SB_DQ<24>";
106"M_I_CPU1_SB_DQ<23>";
107"M_I_CPU1_SB_DQ<5>";
108"M_I_CPU1_SB_DQ<11>";
109"M_I_CPU1_SB_DQ<4>";
110"M_I_CPU1_SB_DQ<10>";
111"M_I_CPU1_SB_DQ<3>";
112"M_I_CPU1_SB_DQ<2>";
113"M_I_CPU1_SB_DQ<19>";
114"M_I_CPU1_SB_DQ<18>";
115"M_I_CPU1_SB_DQ<17>";
116"M_I_CPU1_SB_DQ<16>";
117"M_I_CPU1_SB_DQ<9>";
118"M_I_CPU1_SB_DQ<15>";
119"M_I_CPU1_SB_DQ<8>";
120"M_I_CPU1_SB_DQ<14>";
121"M_I_CPU1_SB_DQ<7>";
122"M_I_CPU1_SB_DQ<13>";
123"M_I_CPU1_SB_DQ<6>";
124"M_I_CPU1_SB_DQ<12>";
125"M_I_CPU1_SA_DQ<17>";
126"M_I_CPU1_SA_DQ<28>";
127"M_I_CPU1_SA_DQ<16>";
128"M_I_CPU1_SA_DQ<27>";
129"M_I_CPU1_SA_DQ<26>";
130"M_I_CPU1_SA_DQ<25>";
131"M_I_CPU1_SA_DQ<24>";
132"M_I_CPU1_SB_DQ<1>";
133"M_I_CPU1_SA_DQ<23>";
134"M_I_CPU1_SB_DQ<0>";
135"M_I_CPU1_SA_DQ<22>";
136"M_I_CPU1_SA_DQ<21>";
137"M_I_CPU1_SA_DQ<20>";
138"M_I_CPU1_SA_DQ<31>";
139"M_I_CPU1_SA_DQ<30>";
140"M_I_CPU1_SA_DQ<19>";
141"M_I_CPU1_SA_DQ<18>";
142"M_I_CPU1_SA_DQ<29>";
143"M_I_CPU1_SA_DQ<5>";
144"M_I_CPU1_SA_DQ<4>";
145"M_I_CPU1_SA_DQ<3>";
146"M_I_CPU1_SA_DQ<15>";
147"M_I_CPU1_SA_DQ<2>";
148"M_I_CPU1_SA_DQ<14>";
149"M_I_CPU1_SA_DQ<1>";
150"M_I_CPU1_SA_DQ<13>";
151"M_I_CPU1_SA_DQ<0>";
152"M_I_CPU1_SA_DQ<12>";
153"M_I_CPU1_SA_DQ<11>";
154"M_I_CPU1_SA_DQ<10>";
155"M_I_CPU1_SA_DQ<9>";
156"M_I_CPU1_SA_DQ<8>";
157"M_I_CPU1_SA_DQ<7>";
158"M_I_CPU1_SA_DQ<6>";
%"GENOA_SP5"
"9","(-4500,3575)","0","pure_quanta","I159";
;
LOCATION"U26"
$SEC"9"
CDS_SEC"9"
PART_TYPE"SMLF"
MATERIAL"IO"
VALUE"SOCKET6096_13568-001"
PART_NUMBER"DGA^6000030"
NEEDS_NO_SIZE"TRUE"
CDS_LMAN_SYM_OUTLINE"-650,2525,650,-2525"
CDS_LIB"pure_quanta";
"TEST39I"
$PN"BF21"12;
"MIA_DATA5"
$PN"K21"143;
"MIA_DATA17"
$PN"V21"125;
"MIA_DATA28"
$PN"AG19"126;
"MIA_DQS_H0"
$PN"G19"75;
"MIA_DQS_L4"
$PN"AM20"62;
"MIB_CHECK2"
$PN"CA19"79;
"MIB_DATA5"
$PN"CG21"107;
"MIB_DATA11"
$PN"CK21"108;
"MIB_DATA22"
$PN"CW19"88;
"MI_ALERT_L"
$PN"AT21"13;
"MIA0_RSP_L"
$PN"BN21"17;
"MIA1_RSP_L"
$PN"BP21"0;
"MIA_CHECK7"
$PN"AR21"80;
"MIA_DATA4"
$PN"J19"144;
"MIA_DATA16"
$PN"U19"127;
"MIA_DATA27"
$PN"AE21"128;
"MIA_DQS_L3"
$PN"AF20"63;
"MIB_CHECK1"
$PN"CA21"81;
"MIB_DATA4"
$PN"CF20"109;
"MIB_DATA10"
$PN"CJ19"110;
"MIB_DATA21"
$PN"CW21"89;
"MIB_PAR"
$PN"BL21"23;
"MIA_CHECK6"
$PN"AP20"90;
"MIA_DATA3"
$PN"G21"145;
"MIA_DATA15"
$PN"U21"146;
"MIA_DATA26"
$PN"AD20"129;
"MIA_DQS_L2"
$PN"Y20"64;
"MIA_PAR"
$PN"BC21"19;
"MIB1_CS_L1"
$PN"BM20"0;
"MIB_CHECK0"
$PN"BY20"82;
"MIB_DATA3"
$PN"CD21"111;
"MIB_DATA20"
$PN"CV20"91;
"MIB_DATA31"
$PN"DF21"92;
"MIB_DQS_H9"
$PN"BV20"41;
"MIA_CHECK5"
$PN"AP21"93;
"MIA_DATA2"
$PN"F20"147;
"MIA_DATA14"
$PN"T20"148;
"MIA_DATA25"
$PN"AD21"130;
"MIA_DQS_L1"
$PN"P20"65;
"MIB0_CS_L1"
$PN"BN19"21;
"MIB1_CS_L0"
$PN"BL19"0;
"MIB_DATA2"
$PN"CC19"112;
"MIB_DATA30"
$PN"DE19"94;
"MIB_DQS_H8"
$PN"DD21"52;
"MIA_CHECK4"
$PN"AN19"95;
"MIA_DATA1"
$PN"F21"149;
"MIA_DATA13"
$PN"T21"150;
"MIA_DATA24"
$PN"AC19"131;
"MIA_DQS_L0"
$PN"H20"66;
"MIB0_CS_L0"
$PN"BM21"20;
"MIB_DATA1"
$PN"CC21"132;
"MIB_DQS_H7"
$PN"CV21"53;
"MIA_CHECK3"
$PN"AL21"96;
"MIA_DATA0"
$PN"E19"151;
"MIA_DATA12"
$PN"R19"152;
"MIA_DATA23"
$PN"AC21"133;
"MIB_DATA0"
$PN"CB20"134;
"MIB_DQS_H6"
$PN"CM21"54;
"MI_RESET_L"
$PN"AU21"24;
"MI0_CLK_L"
$PN"BD20"15;
"MI1_CLK_L"
$PN"BG19"0;
"MIA_CHECK2"
$PN"AK20"97;
"MIA_DATA11"
$PN"N21"153;
"MIA_DATA22"
$PN"AB20"135;
"MIB_DQS_H5"
$PN"CF21"55;
"MIB_DQS_L9"
$PN"BW19"25;
"MIA_CHECK1"
$PN"AK21"98;
"MIA_DATA10"
$PN"M20"154;
"MIA_DATA21"
$PN"AB21"136;
"MIB_DQS_H4"
$PN"BY21"56;
"MIB_DQS_L8"
$PN"DC21"26;
"MIA_CHECK0"
$PN"AJ19"99;
"MIA_DATA20"
$PN"AA19"137;
"MIA_DATA31"
$PN"AJ21"138;
"MIA_DQS_H9"
$PN"AN21"58;
"MIB_CA6"
$PN"BK20"27;
"MIB_DQS_H3"
$PN"DB20"57;
"MIB_DQS_L7"
$PN"CU21"42;
"MIA0_CS_L1"
$PN"AV21"16;
"MIA1_CS_L1"
$PN"AW21"0;
"MIA_CA6"
$PN"BB21"28;
"MIA_DATA30"
$PN"AH20"139;
"MIA_DQS_H8"
$PN"AG21"70;
"MIB_CA5"
$PN"BK21"29;
"MIB_DATA19"
$PN"CT21"113;
"MIB_DQS_H2"
$PN"CT20"59;
"MIB_DQS_L6"
$PN"CL21"43;
"MI0_CLK_H"
$PN"BC19"14;
"MI1_CLK_H"
$PN"BF20"0;
"MIA0_CS_L0"
$PN"AU19"18;
"MIA1_CS_L0"
$PN"AV20"0;
"MIA_CA5"
$PN"BB20"30;
"MIA_DQS_H7"
$PN"AA21"71;
"MIB_CA4"
$PN"BJ21"31;
"MIB_DATA18"
$PN"CR19"114;
"MIB_DATA29"
$PN"DE21"100;
"MIB_DQS_H1"
$PN"CK20"60;
"MIB_DQS_L5"
$PN"CE21"44;
"MIA_CA4"
$PN"BA19"32;
"MIA_DQS_H6"
$PN"R21"72;
"MIB1_RSP_L"
$PN"BR19"0;
"MIB_CA3"
$PN"BJ19"33;
"MIB_DATA17"
$PN"CR21"115;
"MIB_DATA28"
$PN"DD20"101;
"MIB_DQS_H0"
$PN"CD20"61;
"MIB_DQS_L4"
$PN"BW21"45;
"MIA_CA3"
$PN"BA21"34;
"MIA_DQS_H5"
$PN"J21"73;
"MIA_DQS_L9"
$PN"AM21"46;
"MIB0_RSP_L"
$PN"BP20"22;
"MIB_CA2"
$PN"BH20"35;
"MIB_CHECK7"
$PN"BV21"83;
"MIB_DATA16"
$PN"CP20"116;
"MIB_DATA27"
$PN"DB21"102;
"MIB_DQS_L3"
$PN"DC19"47;
"MIA_CA2"
$PN"AY21"36;
"MIA_DATA9"
$PN"M21"155;
"MIA_DQS_H4"
$PN"AL19"74;
"MIA_DQS_L8"
$PN"AF21"48;
"MIB_CA1"
$PN"BH21"37;
"MIB_CHECK6"
$PN"BU19"84;
"MIB_DATA9"
$PN"CJ21"117;
"MIB_DATA15"
$PN"CP21"118;
"MIB_DATA26"
$PN"DA19"103;
"MIB_DQS_L2"
$PN"CU19"49;
"MIA_CA1"
$PN"AY20"38;
"MIA_DATA8"
$PN"L19"156;
"MIA_DQS_H3"
$PN"AE19"76;
"MIA_DQS_L7"
$PN"Y21"67;
"MIB_CA0"
$PN"BG21"39;
"MIB_CHECK5"
$PN"BU21"85;
"MIB_DATA8"
$PN"CH20"119;
"MIB_DATA14"
$PN"CN19"120;
"MIB_DATA25"
$PN"DA21"104;
"MIB_DQS_L1"
$PN"CL19"50;
"MIA_CA0"
$PN"AW19"40;
"MIA_DATA7"
$PN"L21"157;
"MIA_DATA19"
$PN"W21"140;
"MIA_DQS_H2"
$PN"W19"77;
"MIA_DQS_L6"
$PN"P21"68;
"MIB_CHECK4"
$PN"BT20"86;
"MIB_DATA7"
$PN"CH21"121;
"MIB_DATA13"
$PN"CN21"122;
"MIB_DATA24"
$PN"CY20"105;
"MIB_DQS_L0"
$PN"CE19"51;
"MIA_DATA6"
$PN"K20"158;
"MIA_DATA18"
$PN"V20"141;
"MIA_DATA29"
$PN"AH21"142;
"MIA_DQS_H1"
$PN"N19"78;
"MIA_DQS_L5"
$PN"H21"69;
"MIB_CHECK3"
$PN"CB21"87;
"MIB_DATA6"
$PN"CG19"123;
"MIB_DATA12"
$PN"CM20"124;
"MIB_DATA23"
$PN"CY21"106;
%"TAP"
"1","(-3225,5900)","0","mstr_standard","I162";
;
CDS_LIB"mstr_standard"
BODY_TYPE"PLUMBING"
HDL_TAP"TRUE";
"B \NAC \NWC"1;
"S \NAC"
BN"1"149;
%"TAP"
"1","(-3225,5950)","0","mstr_standard","I163";
;
CDS_LIB"mstr_standard"
BODY_TYPE"PLUMBING"
HDL_TAP"TRUE";
"B \NAC \NWC"1;
"S \NAC"
BN"0"151;
%"TAP"
"1","(-3225,5800)","0","mstr_standard","I164";
;
CDS_LIB"mstr_standard"
BODY_TYPE"PLUMBING"
HDL_TAP"TRUE";
"B \NAC \NWC"1;
"S \NAC"
BN"3"145;
%"TAP"
"1","(-3225,5850)","0","mstr_standard","I165";
;
CDS_LIB"mstr_standard"
BODY_TYPE"PLUMBING"
HDL_TAP"TRUE";
"B \NAC \NWC"1;
"S \NAC"
BN"2"147;
%"TAP"
"1","(-3225,5750)","0","mstr_standard","I166";
;
CDS_LIB"mstr_standard"
BODY_TYPE"PLUMBING"
HDL_TAP"TRUE";
"B \NAC \NWC"1;
"S \NAC"
BN"4"144;
%"TAP"
"1","(-3225,5650)","0","mstr_standard","I167";
;
CDS_LIB"mstr_standard"
BODY_TYPE"PLUMBING"
HDL_TAP"TRUE";
"B \NAC \NWC"1;
"S \NAC"
BN"6"158;
%"TAP"
"1","(-3225,5700)","0","mstr_standard","I168";
;
CDS_LIB"mstr_standard"
BODY_TYPE"PLUMBING"
HDL_TAP"TRUE";
"B \NAC \NWC"1;
"S \NAC"
BN"5"143;
%"TAP"
"1","(-3225,5500)","0","mstr_standard","I169";
;
CDS_LIB"mstr_standard"
BODY_TYPE"PLUMBING"
HDL_TAP"TRUE";
"B \NAC \NWC"1;
"S \NAC"
BN"8"156;
%"TAP"
"1","(-3225,5600)","0","mstr_standard","I170";
;
CDS_LIB"mstr_standard"
BODY_TYPE"PLUMBING"
HDL_TAP"TRUE";
"B \NAC \NWC"1;
"S \NAC"
BN"7"157;
%"TAP"
"1","(-3225,5400)","0","mstr_standard","I171";
;
CDS_LIB"mstr_standard"
BODY_TYPE"PLUMBING"
HDL_TAP"TRUE";
"B \NAC \NWC"1;
"S \NAC"
BN"10"154;
%"TAP"
"1","(-3225,5450)","0","mstr_standard","I172";
;
CDS_LIB"mstr_standard"
BODY_TYPE"PLUMBING"
HDL_TAP"TRUE";
"B \NAC \NWC"1;
"S \NAC"
BN"9"155;
%"TAP"
"1","(-3225,5250)","0","mstr_standard","I173";
;
CDS_LIB"mstr_standard"
BODY_TYPE"PLUMBING"
HDL_TAP"TRUE";
"B \NAC \NWC"1;
"S \NAC"
BN"13"150;
%"TAP"
"1","(-3225,5300)","0","mstr_standard","I174";
;
CDS_LIB"mstr_standard"
BODY_TYPE"PLUMBING"
HDL_TAP"TRUE";
"B \NAC \NWC"1;
"S \NAC"
BN"12"152;
%"TAP"
"1","(-3225,5350)","0","mstr_standard","I175";
;
CDS_LIB"mstr_standard"
BODY_TYPE"PLUMBING"
HDL_TAP"TRUE";
"B \NAC \NWC"1;
"S \NAC"
BN"11"153;
%"TAP"
"1","(-3225,5200)","0","mstr_standard","I176";
;
CDS_LIB"mstr_standard"
BODY_TYPE"PLUMBING"
HDL_TAP"TRUE";
"B \NAC \NWC"1;
"S \NAC"
BN"14"148;
%"TAP"
"1","(-3225,5150)","0","mstr_standard","I177";
;
CDS_LIB"mstr_standard"
BODY_TYPE"PLUMBING"
HDL_TAP"TRUE";
"B \NAC \NWC"1;
"S \NAC"
BN"15"146;
%"TAP"
"1","(-3225,5050)","0","mstr_standard","I178";
;
CDS_LIB"mstr_standard"
BODY_TYPE"PLUMBING"
HDL_TAP"TRUE";
"B \NAC \NWC"1;
"S \NAC"
BN"16"127;
%"TAP"
"1","(-3225,5000)","0","mstr_standard","I179";
;
CDS_LIB"mstr_standard"
BODY_TYPE"PLUMBING"
HDL_TAP"TRUE";
"B \NAC \NWC"1;
"S \NAC"
BN"17"125;
%"TAP"
"1","(-3225,4900)","0","mstr_standard","I180";
;
CDS_LIB"mstr_standard"
BODY_TYPE"PLUMBING"
HDL_TAP"TRUE";
"B \NAC \NWC"1;
"S \NAC"
BN"19"140;
%"TAP"
"1","(-3225,4950)","0","mstr_standard","I181";
;
CDS_LIB"mstr_standard"
BODY_TYPE"PLUMBING"
HDL_TAP"TRUE";
"B \NAC \NWC"1;
"S \NAC"
BN"18"141;
%"TAP"
"1","(-3225,4850)","0","mstr_standard","I182";
;
CDS_LIB"mstr_standard"
BODY_TYPE"PLUMBING"
HDL_TAP"TRUE";
"B \NAC \NWC"1;
"S \NAC"
BN"20"137;
%"TAP"
"1","(-3225,4750)","0","mstr_standard","I183";
;
CDS_LIB"mstr_standard"
BODY_TYPE"PLUMBING"
HDL_TAP"TRUE";
"B \NAC \NWC"1;
"S \NAC"
BN"22"135;
%"TAP"
"1","(-3225,4800)","0","mstr_standard","I184";
;
CDS_LIB"mstr_standard"
BODY_TYPE"PLUMBING"
HDL_TAP"TRUE";
"B \NAC \NWC"1;
"S \NAC"
BN"21"136;
%"TAP"
"1","(-3225,4700)","0","mstr_standard","I185";
;
CDS_LIB"mstr_standard"
BODY_TYPE"PLUMBING"
HDL_TAP"TRUE";
"B \NAC \NWC"1;
"S \NAC"
BN"23"133;
%"TAP"
"1","(-3225,4500)","0","mstr_standard","I186";
;
CDS_LIB"mstr_standard"
BODY_TYPE"PLUMBING"
HDL_TAP"TRUE";
"B \NAC \NWC"1;
"S \NAC"
BN"26"129;
%"TAP"
"1","(-3225,4600)","0","mstr_standard","I187";
;
CDS_LIB"mstr_standard"
BODY_TYPE"PLUMBING"
HDL_TAP"TRUE";
"B \NAC \NWC"1;
"S \NAC"
BN"24"131;
%"TAP"
"1","(-3225,4550)","0","mstr_standard","I188";
;
CDS_LIB"mstr_standard"
BODY_TYPE"PLUMBING"
HDL_TAP"TRUE";
"B \NAC \NWC"1;
"S \NAC"
BN"25"130;
%"TAP"
"1","(-3225,4400)","0","mstr_standard","I189";
;
CDS_LIB"mstr_standard"
BODY_TYPE"PLUMBING"
HDL_TAP"TRUE";
"B \NAC \NWC"1;
"S \NAC"
BN"28"126;
%"TAP"
"1","(-3225,4450)","0","mstr_standard","I190";
;
CDS_LIB"mstr_standard"
BODY_TYPE"PLUMBING"
HDL_TAP"TRUE";
"B \NAC \NWC"1;
"S \NAC"
BN"27"128;
%"TAP"
"1","(-3225,4350)","0","mstr_standard","I191";
;
CDS_LIB"mstr_standard"
BODY_TYPE"PLUMBING"
HDL_TAP"TRUE";
"B \NAC \NWC"1;
"S \NAC"
BN"29"142;
%"TAP"
"1","(-3225,4300)","0","mstr_standard","I192";
;
CDS_LIB"mstr_standard"
BODY_TYPE"PLUMBING"
HDL_TAP"TRUE";
"B \NAC \NWC"1;
"S \NAC"
BN"30"139;
%"TAP"
"1","(-3225,4250)","0","mstr_standard","I193";
;
CDS_LIB"mstr_standard"
BODY_TYPE"PLUMBING"
HDL_TAP"TRUE";
"B \NAC \NWC"1;
"S \NAC"
BN"31"138;
%"TAP"
"1","(-3225,4150)","0","mstr_standard","I194";
;
CDS_LIB"mstr_standard"
BODY_TYPE"PLUMBING"
HDL_TAP"TRUE";
"B \NAC \NWC"2;
"S \NAC"
BN"0"134;
%"TAP"
"1","(-3225,4100)","0","mstr_standard","I195";
;
CDS_LIB"mstr_standard"
BODY_TYPE"PLUMBING"
HDL_TAP"TRUE";
"B \NAC \NWC"2;
"S \NAC"
BN"1"132;
%"TAP"
"1","(-3225,4050)","0","mstr_standard","I197";
;
CDS_LIB"mstr_standard"
BODY_TYPE"PLUMBING"
HDL_TAP"TRUE";
"B \NAC \NWC"2;
"S \NAC"
BN"2"112;
%"TAP"
"1","(-3225,4000)","0","mstr_standard","I198";
;
CDS_LIB"mstr_standard"
BODY_TYPE"PLUMBING"
HDL_TAP"TRUE";
"B \NAC \NWC"2;
"S \NAC"
BN"3"111;
%"TAP"
"1","(-3225,3950)","0","mstr_standard","I199";
;
CDS_LIB"mstr_standard"
BODY_TYPE"PLUMBING"
HDL_TAP"TRUE";
"B \NAC \NWC"2;
"S \NAC"
BN"4"109;
%"TAP"
"1","(-3225,3900)","0","mstr_standard","I200";
;
CDS_LIB"mstr_standard"
BODY_TYPE"PLUMBING"
HDL_TAP"TRUE";
"B \NAC \NWC"2;
"S \NAC"
BN"5"107;
%"TAP"
"1","(-3225,3850)","0","mstr_standard","I201";
;
CDS_LIB"mstr_standard"
BODY_TYPE"PLUMBING"
HDL_TAP"TRUE";
"B \NAC \NWC"2;
"S \NAC"
BN"6"123;
%"TAP"
"1","(-3225,3800)","0","mstr_standard","I202";
;
CDS_LIB"mstr_standard"
BODY_TYPE"PLUMBING"
HDL_TAP"TRUE";
"B \NAC \NWC"2;
"S \NAC"
BN"7"121;
%"TAP"
"1","(-3225,3700)","0","mstr_standard","I203";
;
CDS_LIB"mstr_standard"
BODY_TYPE"PLUMBING"
HDL_TAP"TRUE";
"B \NAC \NWC"2;
"S \NAC"
BN"8"119;
%"TAP"
"1","(-3225,3650)","0","mstr_standard","I204";
;
CDS_LIB"mstr_standard"
BODY_TYPE"PLUMBING"
HDL_TAP"TRUE";
"B \NAC \NWC"2;
"S \NAC"
BN"9"117;
%"TAP"
"1","(-3225,3600)","0","mstr_standard","I205";
;
CDS_LIB"mstr_standard"
BODY_TYPE"PLUMBING"
HDL_TAP"TRUE";
"B \NAC \NWC"2;
"S \NAC"
BN"10"110;
%"TAP"
"1","(-3225,3550)","0","mstr_standard","I206";
;
CDS_LIB"mstr_standard"
BODY_TYPE"PLUMBING"
HDL_TAP"TRUE";
"B \NAC \NWC"2;
"S \NAC"
BN"11"108;
%"TAP"
"1","(-3225,3500)","0","mstr_standard","I207";
;
CDS_LIB"mstr_standard"
BODY_TYPE"PLUMBING"
HDL_TAP"TRUE";
"B \NAC \NWC"2;
"S \NAC"
BN"12"124;
%"TAP"
"1","(-3225,3450)","0","mstr_standard","I208";
;
CDS_LIB"mstr_standard"
BODY_TYPE"PLUMBING"
HDL_TAP"TRUE";
"B \NAC \NWC"2;
"S \NAC"
BN"13"122;
%"TAP"
"1","(-3225,3350)","0","mstr_standard","I209";
;
CDS_LIB"mstr_standard"
BODY_TYPE"PLUMBING"
HDL_TAP"TRUE";
"B \NAC \NWC"2;
"S \NAC"
BN"15"118;
%"TAP"
"1","(-3225,3400)","0","mstr_standard","I210";
;
CDS_LIB"mstr_standard"
BODY_TYPE"PLUMBING"
HDL_TAP"TRUE";
"B \NAC \NWC"2;
"S \NAC"
BN"14"120;
%"TAP"
"1","(-3225,3250)","0","mstr_standard","I211";
;
CDS_LIB"mstr_standard"
BODY_TYPE"PLUMBING"
HDL_TAP"TRUE";
"B \NAC \NWC"2;
"S \NAC"
BN"16"116;
%"TAP"
"1","(-3225,3200)","0","mstr_standard","I212";
;
CDS_LIB"mstr_standard"
BODY_TYPE"PLUMBING"
HDL_TAP"TRUE";
"B \NAC \NWC"2;
"S \NAC"
BN"17"115;
%"TAP"
"1","(-3225,3150)","0","mstr_standard","I213";
;
CDS_LIB"mstr_standard"
BODY_TYPE"PLUMBING"
HDL_TAP"TRUE";
"B \NAC \NWC"2;
"S \NAC"
BN"18"114;
%"TAP"
"1","(-3225,3100)","0","mstr_standard","I214";
;
CDS_LIB"mstr_standard"
BODY_TYPE"PLUMBING"
HDL_TAP"TRUE";
"B \NAC \NWC"2;
"S \NAC"
BN"19"113;
%"TAP"
"1","(-3225,3000)","0","mstr_standard","I215";
;
CDS_LIB"mstr_standard"
BODY_TYPE"PLUMBING"
HDL_TAP"TRUE";
"B \NAC \NWC"2;
"S \NAC"
BN"21"89;
%"TAP"
"1","(-3225,2900)","0","mstr_standard","I216";
;
CDS_LIB"mstr_standard"
BODY_TYPE"PLUMBING"
HDL_TAP"TRUE";
"B \NAC \NWC"2;
"S \NAC"
BN"23"106;
%"TAP"
"1","(-3225,3050)","0","mstr_standard","I217";
;
CDS_LIB"mstr_standard"
BODY_TYPE"PLUMBING"
HDL_TAP"TRUE";
"B \NAC \NWC"2;
"S \NAC"
BN"20"91;
%"TAP"
"1","(-3225,2950)","0","mstr_standard","I218";
;
CDS_LIB"mstr_standard"
BODY_TYPE"PLUMBING"
HDL_TAP"TRUE";
"B \NAC \NWC"2;
"S \NAC"
BN"22"88;
%"TAP"
"1","(-3225,2800)","0","mstr_standard","I219";
;
CDS_LIB"mstr_standard"
BODY_TYPE"PLUMBING"
HDL_TAP"TRUE";
"B \NAC \NWC"2;
"S \NAC"
BN"24"105;
%"TAP"
"1","(-3225,2750)","0","mstr_standard","I220";
;
CDS_LIB"mstr_standard"
BODY_TYPE"PLUMBING"
HDL_TAP"TRUE";
"B \NAC \NWC"2;
"S \NAC"
BN"25"104;
%"TAP"
"1","(-3225,2700)","0","mstr_standard","I221";
;
CDS_LIB"mstr_standard"
BODY_TYPE"PLUMBING"
HDL_TAP"TRUE";
"B \NAC \NWC"2;
"S \NAC"
BN"26"103;
%"TAP"
"1","(-3225,2600)","0","mstr_standard","I222";
;
CDS_LIB"mstr_standard"
BODY_TYPE"PLUMBING"
HDL_TAP"TRUE";
"B \NAC \NWC"2;
"S \NAC"
BN"28"101;
%"TAP"
"1","(-3225,2650)","0","mstr_standard","I223";
;
CDS_LIB"mstr_standard"
BODY_TYPE"PLUMBING"
HDL_TAP"TRUE";
"B \NAC \NWC"2;
"S \NAC"
BN"27"102;
%"TAP"
"1","(-3225,2500)","0","mstr_standard","I224";
;
CDS_LIB"mstr_standard"
BODY_TYPE"PLUMBING"
HDL_TAP"TRUE";
"B \NAC \NWC"2;
"S \NAC"
BN"30"94;
%"TAP"
"1","(-3225,2550)","0","mstr_standard","I225";
;
CDS_LIB"mstr_standard"
BODY_TYPE"PLUMBING"
HDL_TAP"TRUE";
"B \NAC \NWC"2;
"S \NAC"
BN"29"100;
%"TAP"
"1","(-3225,2450)","0","mstr_standard","I226";
;
CDS_LIB"mstr_standard"
BODY_TYPE"PLUMBING"
HDL_TAP"TRUE";
"B \NAC \NWC"2;
"S \NAC"
BN"31"92;
%"TAP"
"1","(-3225,2350)","0","mstr_standard","I227";
;
CDS_LIB"mstr_standard"
BODY_TYPE"PLUMBING"
HDL_TAP"TRUE";
"B \NAC \NWC"3;
"S \NAC"
BN"0"99;
%"TAP"
"1","(-3225,2300)","0","mstr_standard","I228";
;
CDS_LIB"mstr_standard"
BODY_TYPE"PLUMBING"
HDL_TAP"TRUE";
"B \NAC \NWC"3;
"S \NAC"
BN"1"98;
%"TAP"
"1","(-3225,2200)","0","mstr_standard","I229";
;
CDS_LIB"mstr_standard"
BODY_TYPE"PLUMBING"
HDL_TAP"TRUE";
"B \NAC \NWC"3;
"S \NAC"
BN"3"96;
%"TAP"
"1","(-3225,2250)","0","mstr_standard","I230";
;
CDS_LIB"mstr_standard"
BODY_TYPE"PLUMBING"
HDL_TAP"TRUE";
"B \NAC \NWC"3;
"S \NAC"
BN"2"97;
%"TAP"
"1","(-3225,2050)","0","mstr_standard","I231";
;
CDS_LIB"mstr_standard"
BODY_TYPE"PLUMBING"
HDL_TAP"TRUE";
"B \NAC \NWC"3;
"S \NAC"
BN"6"90;
%"TAP"
"1","(-3225,2100)","0","mstr_standard","I232";
;
CDS_LIB"mstr_standard"
BODY_TYPE"PLUMBING"
HDL_TAP"TRUE";
"B \NAC \NWC"3;
"S \NAC"
BN"5"93;
%"TAP"
"1","(-3225,2150)","0","mstr_standard","I233";
;
CDS_LIB"mstr_standard"
BODY_TYPE"PLUMBING"
HDL_TAP"TRUE";
"B \NAC \NWC"3;
"S \NAC"
BN"4"95;
%"TAP"
"1","(-3225,1900)","0","mstr_standard","I235";
;
CDS_LIB"mstr_standard"
BODY_TYPE"PLUMBING"
HDL_TAP"TRUE";
"B \NAC \NWC"4;
"S \NAC"
BN"0"82;
%"TAP"
"1","(-3225,2000)","0","mstr_standard","I236";
;
CDS_LIB"mstr_standard"
BODY_TYPE"PLUMBING"
HDL_TAP"TRUE";
"B \NAC \NWC"3;
"S \NAC"
BN"7"80;
%"TAP"
"1","(-3225,1800)","0","mstr_standard","I237";
;
CDS_LIB"mstr_standard"
BODY_TYPE"PLUMBING"
HDL_TAP"TRUE";
"B \NAC \NWC"4;
"S \NAC"
BN"2"79;
%"TAP"
"1","(-3225,1850)","0","mstr_standard","I238";
;
CDS_LIB"mstr_standard"
BODY_TYPE"PLUMBING"
HDL_TAP"TRUE";
"B \NAC \NWC"4;
"S \NAC"
BN"1"81;
%"TAP"
"1","(-3225,1750)","0","mstr_standard","I239";
;
CDS_LIB"mstr_standard"
BODY_TYPE"PLUMBING"
HDL_TAP"TRUE";
"B \NAC \NWC"4;
"S \NAC"
BN"3"87;
%"TAP"
"1","(-3225,1700)","0","mstr_standard","I240";
;
CDS_LIB"mstr_standard"
BODY_TYPE"PLUMBING"
HDL_TAP"TRUE";
"B \NAC \NWC"4;
"S \NAC"
BN"4"86;
%"TAP"
"1","(-3225,1650)","0","mstr_standard","I241";
;
CDS_LIB"mstr_standard"
BODY_TYPE"PLUMBING"
HDL_TAP"TRUE";
"B \NAC \NWC"4;
"S \NAC"
BN"5"85;
%"TAP"
"1","(-3225,1550)","0","mstr_standard","I242";
;
CDS_LIB"mstr_standard"
BODY_TYPE"PLUMBING"
HDL_TAP"TRUE";
"B \NAC \NWC"4;
"S \NAC"
BN"7"83;
%"TAP"
"1","(-3225,1600)","0","mstr_standard","I243";
;
CDS_LIB"mstr_standard"
BODY_TYPE"PLUMBING"
HDL_TAP"TRUE";
"B \NAC \NWC"4;
"S \NAC"
BN"6"84;
%"TAP"
"1","(-5650,5950)","2","mstr_standard","I244";
;
CDS_LIB"mstr_standard"
BODY_TYPE"PLUMBING"
HDL_TAP"TRUE";
"B \NAC \NWC"5;
"S \NAC"
BN"0"75;
%"TAP"
"1","(-5650,5850)","2","mstr_standard","I245";
;
CDS_LIB"mstr_standard"
BODY_TYPE"PLUMBING"
HDL_TAP"TRUE";
"B \NAC \NWC"5;
"S \NAC"
BN"1"78;
%"TAP"
"1","(-5650,5750)","2","mstr_standard","I246";
;
CDS_LIB"mstr_standard"
BODY_TYPE"PLUMBING"
HDL_TAP"TRUE";
"B \NAC \NWC"5;
"S \NAC"
BN"2"77;
%"TAP"
"1","(-5650,5650)","2","mstr_standard","I247";
;
CDS_LIB"mstr_standard"
BODY_TYPE"PLUMBING"
HDL_TAP"TRUE";
"B \NAC \NWC"5;
"S \NAC"
BN"3"76;
%"TAP"
"1","(-5650,5450)","2","mstr_standard","I248";
;
CDS_LIB"mstr_standard"
BODY_TYPE"PLUMBING"
HDL_TAP"TRUE";
"B \NAC \NWC"5;
"S \NAC"
BN"5"73;
%"TAP"
"1","(-5650,5550)","2","mstr_standard","I249";
;
CDS_LIB"mstr_standard"
BODY_TYPE"PLUMBING"
HDL_TAP"TRUE";
"B \NAC \NWC"5;
"S \NAC"
BN"4"74;
%"TAP"
"1","(-5650,5350)","2","mstr_standard","I250";
;
CDS_LIB"mstr_standard"
BODY_TYPE"PLUMBING"
HDL_TAP"TRUE";
"B \NAC \NWC"5;
"S \NAC"
BN"6"72;
%"TAP"
"1","(-5650,5250)","2","mstr_standard","I251";
;
CDS_LIB"mstr_standard"
BODY_TYPE"PLUMBING"
HDL_TAP"TRUE";
"B \NAC \NWC"5;
"S \NAC"
BN"7"71;
%"TAP"
"1","(-5650,5150)","2","mstr_standard","I252";
;
CDS_LIB"mstr_standard"
BODY_TYPE"PLUMBING"
HDL_TAP"TRUE";
"B \NAC \NWC"5;
"S \NAC"
BN"8"70;
%"TAP"
"1","(-5850,5900)","2","mstr_standard","I253";
;
CDS_LIB"mstr_standard"
BODY_TYPE"PLUMBING"
HDL_TAP"TRUE";
"B \NAC \NWC"9;
"S \NAC"
BN"0"66;
%"TAP"
"1","(-5850,5700)","2","mstr_standard","I254";
;
CDS_LIB"mstr_standard"
BODY_TYPE"PLUMBING"
HDL_TAP"TRUE";
"B \NAC \NWC"9;
"S \NAC"
BN"2"64;
%"TAP"
"1","(-5850,5800)","2","mstr_standard","I255";
;
CDS_LIB"mstr_standard"
BODY_TYPE"PLUMBING"
HDL_TAP"TRUE";
"B \NAC \NWC"9;
"S \NAC"
BN"1"65;
%"TAP"
"1","(-5850,5400)","2","mstr_standard","I256";
;
CDS_LIB"mstr_standard"
BODY_TYPE"PLUMBING"
HDL_TAP"TRUE";
"B \NAC \NWC"9;
"S \NAC"
BN"5"69;
%"TAP"
"1","(-5850,5600)","2","mstr_standard","I257";
;
CDS_LIB"mstr_standard"
BODY_TYPE"PLUMBING"
HDL_TAP"TRUE";
"B \NAC \NWC"9;
"S \NAC"
BN"3"63;
%"TAP"
"1","(-5850,5500)","2","mstr_standard","I258";
;
CDS_LIB"mstr_standard"
BODY_TYPE"PLUMBING"
HDL_TAP"TRUE";
"B \NAC \NWC"9;
"S \NAC"
BN"4"62;
%"TAP"
"1","(-5850,5200)","2","mstr_standard","I259";
;
CDS_LIB"mstr_standard"
BODY_TYPE"PLUMBING"
HDL_TAP"TRUE";
"B \NAC \NWC"9;
"S \NAC"
BN"7"67;
%"TAP"
"1","(-5850,5300)","2","mstr_standard","I260";
;
CDS_LIB"mstr_standard"
BODY_TYPE"PLUMBING"
HDL_TAP"TRUE";
"B \NAC \NWC"9;
"S \NAC"
BN"6"68;
%"TAP"
"1","(-5650,4900)","2","mstr_standard","I261";
;
CDS_LIB"mstr_standard"
BODY_TYPE"PLUMBING"
HDL_TAP"TRUE";
"B \NAC \NWC"6;
"S \NAC"
BN"0"61;
%"TAP"
"1","(-5650,5050)","2","mstr_standard","I262";
;
CDS_LIB"mstr_standard"
BODY_TYPE"PLUMBING"
HDL_TAP"TRUE";
"B \NAC \NWC"5;
"S \NAC"
BN"9"58;
%"TAP"
"1","(-5650,4800)","2","mstr_standard","I263";
;
CDS_LIB"mstr_standard"
BODY_TYPE"PLUMBING"
HDL_TAP"TRUE";
"B \NAC \NWC"6;
"S \NAC"
BN"1"60;
%"TAP"
"1","(-5650,4700)","2","mstr_standard","I264";
;
CDS_LIB"mstr_standard"
BODY_TYPE"PLUMBING"
HDL_TAP"TRUE";
"B \NAC \NWC"6;
"S \NAC"
BN"2"59;
%"TAP"
"1","(-5650,4400)","2","mstr_standard","I265";
;
CDS_LIB"mstr_standard"
BODY_TYPE"PLUMBING"
HDL_TAP"TRUE";
"B \NAC \NWC"6;
"S \NAC"
BN"5"55;
%"TAP"
"1","(-5650,4600)","2","mstr_standard","I266";
;
CDS_LIB"mstr_standard"
BODY_TYPE"PLUMBING"
HDL_TAP"TRUE";
"B \NAC \NWC"6;
"S \NAC"
BN"3"57;
%"TAP"
"1","(-5650,4500)","2","mstr_standard","I267";
;
CDS_LIB"mstr_standard"
BODY_TYPE"PLUMBING"
HDL_TAP"TRUE";
"B \NAC \NWC"6;
"S \NAC"
BN"4"56;
%"TAP"
"1","(-5650,4300)","2","mstr_standard","I268";
;
CDS_LIB"mstr_standard"
BODY_TYPE"PLUMBING"
HDL_TAP"TRUE";
"B \NAC \NWC"6;
"S \NAC"
BN"6"54;
%"TAP"
"1","(-5650,4200)","2","mstr_standard","I269";
;
CDS_LIB"mstr_standard"
BODY_TYPE"PLUMBING"
HDL_TAP"TRUE";
"B \NAC \NWC"6;
"S \NAC"
BN"7"53;
%"TAP"
"1","(-5650,4100)","2","mstr_standard","I270";
;
CDS_LIB"mstr_standard"
BODY_TYPE"PLUMBING"
HDL_TAP"TRUE";
"B \NAC \NWC"6;
"S \NAC"
BN"8"52;
%"TAP"
"1","(-5850,5100)","2","mstr_standard","I271";
;
CDS_LIB"mstr_standard"
BODY_TYPE"PLUMBING"
HDL_TAP"TRUE";
"B \NAC \NWC"9;
"S \NAC"
BN"8"48;
%"TAP"
"1","(-5850,5000)","2","mstr_standard","I272";
;
CDS_LIB"mstr_standard"
BODY_TYPE"PLUMBING"
HDL_TAP"TRUE";
"B \NAC \NWC"9;
"S \NAC"
BN"9"46;
%"TAP"
"1","(-5850,4850)","2","mstr_standard","I273";
;
CDS_LIB"mstr_standard"
BODY_TYPE"PLUMBING"
HDL_TAP"TRUE";
"B \NAC \NWC"10;
"S \NAC"
BN"0"51;
%"TAP"
"1","(-5850,4650)","2","mstr_standard","I274";
;
CDS_LIB"mstr_standard"
BODY_TYPE"PLUMBING"
HDL_TAP"TRUE";
"B \NAC \NWC"10;
"S \NAC"
BN"2"49;
%"TAP"
"1","(-5850,4750)","2","mstr_standard","I275";
;
CDS_LIB"mstr_standard"
BODY_TYPE"PLUMBING"
HDL_TAP"TRUE";
"B \NAC \NWC"10;
"S \NAC"
BN"1"50;
%"TAP"
"1","(-5850,4450)","2","mstr_standard","I276";
;
CDS_LIB"mstr_standard"
BODY_TYPE"PLUMBING"
HDL_TAP"TRUE";
"B \NAC \NWC"10;
"S \NAC"
BN"4"45;
%"TAP"
"1","(-5850,4550)","2","mstr_standard","I277";
;
CDS_LIB"mstr_standard"
BODY_TYPE"PLUMBING"
HDL_TAP"TRUE";
"B \NAC \NWC"10;
"S \NAC"
BN"3"47;
%"TAP"
"1","(-5850,4350)","2","mstr_standard","I278";
;
CDS_LIB"mstr_standard"
BODY_TYPE"PLUMBING"
HDL_TAP"TRUE";
"B \NAC \NWC"10;
"S \NAC"
BN"5"44;
%"TAP"
"1","(-5850,4250)","2","mstr_standard","I279";
;
CDS_LIB"mstr_standard"
BODY_TYPE"PLUMBING"
HDL_TAP"TRUE";
"B \NAC \NWC"10;
"S \NAC"
BN"6"43;
%"TAP"
"1","(-5850,4150)","2","mstr_standard","I280";
;
CDS_LIB"mstr_standard"
BODY_TYPE"PLUMBING"
HDL_TAP"TRUE";
"B \NAC \NWC"10;
"S \NAC"
BN"7"42;
%"TAP"
"1","(-5650,4000)","2","mstr_standard","I285";
;
CDS_LIB"mstr_standard"
BODY_TYPE"PLUMBING"
HDL_TAP"TRUE";
"B \NAC \NWC"6;
"S \NAC"
BN"9"41;
%"TAP"
"1","(-5850,3950)","2","mstr_standard","I286";
;
CDS_LIB"mstr_standard"
BODY_TYPE"PLUMBING"
HDL_TAP"TRUE";
"B \NAC \NWC"10;
"S \NAC"
BN"9"25;
%"TAP"
"1","(-5850,4050)","2","mstr_standard","I287";
;
CDS_LIB"mstr_standard"
BODY_TYPE"PLUMBING"
HDL_TAP"TRUE";
"B \NAC \NWC"10;
"S \NAC"
BN"8"26;
%"TAP"
"1","(-5850,3750)","2","mstr_standard","I288";
;
CDS_LIB"mstr_standard"
BODY_TYPE"PLUMBING"
HDL_TAP"TRUE";
"B \NAC \NWC"7;
"S \NAC"
BN"1"38;
%"TAP"
"1","(-5850,3800)","2","mstr_standard","I289";
;
CDS_LIB"mstr_standard"
BODY_TYPE"PLUMBING"
HDL_TAP"TRUE";
"B \NAC \NWC"7;
"S \NAC"
BN"0"40;
%"TAP"
"1","(-5850,3700)","2","mstr_standard","I290";
;
CDS_LIB"mstr_standard"
BODY_TYPE"PLUMBING"
HDL_TAP"TRUE";
"B \NAC \NWC"7;
"S \NAC"
BN"2"36;
%"TAP"
"1","(-5850,3650)","2","mstr_standard","I291";
;
CDS_LIB"mstr_standard"
BODY_TYPE"PLUMBING"
HDL_TAP"TRUE";
"B \NAC \NWC"7;
"S \NAC"
BN"3"34;
%"TAP"
"1","(-5850,3600)","2","mstr_standard","I292";
;
CDS_LIB"mstr_standard"
BODY_TYPE"PLUMBING"
HDL_TAP"TRUE";
"B \NAC \NWC"7;
"S \NAC"
BN"4"32;
%"TAP"
"1","(-5850,3400)","2","mstr_standard","I293";
;
CDS_LIB"mstr_standard"
BODY_TYPE"PLUMBING"
HDL_TAP"TRUE";
"B \NAC \NWC"8;
"S \NAC"
BN"0"39;
%"TAP"
"1","(-5850,3350)","2","mstr_standard","I294";
;
CDS_LIB"mstr_standard"
BODY_TYPE"PLUMBING"
HDL_TAP"TRUE";
"B \NAC \NWC"8;
"S \NAC"
BN"1"37;
%"TAP"
"1","(-5850,3550)","2","mstr_standard","I295";
;
CDS_LIB"mstr_standard"
BODY_TYPE"PLUMBING"
HDL_TAP"TRUE";
"B \NAC \NWC"7;
"S \NAC"
BN"5"30;
%"TAP"
"1","(-5850,3500)","2","mstr_standard","I296";
;
CDS_LIB"mstr_standard"
BODY_TYPE"PLUMBING"
HDL_TAP"TRUE";
"B \NAC \NWC"7;
"S \NAC"
BN"6"28;
%"TAP"
"1","(-5850,3300)","2","mstr_standard","I297";
;
CDS_LIB"mstr_standard"
BODY_TYPE"PLUMBING"
HDL_TAP"TRUE";
"B \NAC \NWC"8;
"S \NAC"
BN"2"35;
%"TAP"
"1","(-5850,3250)","2","mstr_standard","I298";
;
CDS_LIB"mstr_standard"
BODY_TYPE"PLUMBING"
HDL_TAP"TRUE";
"B \NAC \NWC"8;
"S \NAC"
BN"3"33;
%"TAP"
"1","(-5850,3200)","2","mstr_standard","I299";
;
CDS_LIB"mstr_standard"
BODY_TYPE"PLUMBING"
HDL_TAP"TRUE";
"B \NAC \NWC"8;
"S \NAC"
BN"4"31;
%"TAP"
"1","(-5850,3150)","2","mstr_standard","I300";
;
CDS_LIB"mstr_standard"
BODY_TYPE"PLUMBING"
HDL_TAP"TRUE";
"B \NAC \NWC"8;
"S \NAC"
BN"5"29;
%"TAP"
"1","(-5850,3100)","2","mstr_standard","I301";
;
CDS_LIB"mstr_standard"
BODY_TYPE"PLUMBING"
HDL_TAP"TRUE";
"B \NAC \NWC"8;
"S \NAC"
BN"6"27;
%"Q_RES"
"1","(-6525,2100)","0","pure_quanta","I314";
;
LOCATION"R508"
$SEC"1"
CDS_SEC"1"
TOLERANCE"1%"
VALUE"15   "
PART_NUMBER"CS01502FB11"
PACK_TYPE"0402LF"
CDS_LIB"pure_quanta"
WATTAGE"1/16W"
MATERIAL"CHIP";
"B"
$PN"2"13;
"A"
$PN"1"11;
END.
